(kicad_pcb
	(version 20260206)
	(generator "pcbnew")
	(generator_version "10.0")
	(general
		(thickness 1.6)
		(legacy_teardrops no)
	)
	(paper "A4")
	(title_block
		(title "04192023_DAF0TMB3IC0_F0TG_MB_C_brd_V02_OCP.brd")
		(comment 1 "Grand Teton / footprints 2245-2251 of 8354")
	)
	(layers
		(0 "F.Cu" signal "TOP")
		(4 "In1.Cu" signal "GND")
		(6 "In2.Cu" signal "IN1")
		(8 "In3.Cu" signal "GND1")
		(10 "In4.Cu" signal "IN2")
		(12 "In5.Cu" signal "GND2")
		(14 "In6.Cu" signal "IN3")
		(16 "In7.Cu" signal "GND3")
		(18 "In8.Cu" signal "VCC")
		(20 "In9.Cu" signal "VCC1")
		(22 "In10.Cu" signal "GND4")
		(24 "In11.Cu" signal "IN4")
		(26 "In12.Cu" signal "GND5")
		(28 "In13.Cu" signal "IN5")
		(30 "In14.Cu" signal "GND6")
		(32 "In15.Cu" signal "IN6")
		(34 "In16.Cu" signal "GND7")
		(2 "B.Cu" signal "BOTTOM")
		(9 "F.Adhes" user "F.Adhesive")
		(11 "B.Adhes" user "B.Adhesive")
		(13 "F.Paste" user "Package Geometry/Pastemask Top")
		(15 "B.Paste" user "Package Geometry/Pastemask Bottom")
		(5 "F.SilkS" user "Ref Des/Silkscreen Top")
		(7 "B.SilkS" user "Ref Des/Silkscreen Bottom")
		(1 "F.Mask" user "Board Geometry/Soldermask Top")
		(3 "B.Mask" user "Board Geometry/Soldermask Bottom")
		(17 "Dwgs.User" user "User.Drawings")
		(19 "Cmts.User" user "User.Comments")
		(21 "Eco1.User" user "User.Eco1")
		(23 "Eco2.User" user "User.Eco2")
		(25 "Edge.Cuts" user "Board Geometry/Outline")
		(27 "Margin" user)
		(31 "F.CrtYd" user "Package Geometry/Place Bound Top")
		(29 "B.CrtYd" user "Package Geometry/Place Bound Bottom")
		(35 "F.Fab" user "Ref Des/Assembly Top")
		(33 "B.Fab" user "Ref Des/Assembly Bottom")
	)
	(footprint ""
		(layer "F.Cu")
		(at 35.132772 -434.128164)
		(property "Reference" "R2898"
			(at 0 0 0)
			(layer "F.SilkS")
			(hide yes)
			(effects
				(font
					(size 1.27 1.27)
				)
			)
		)
		(property "Value" ""
			(at 0 0 0)
			(layer "F.Fab")
			(effects
				(font
					(size 1.27 1.27)
				)
			)
		)
		(duplicate_pad_numbers_are_jumpers no)
		(fp_line
			(start -0.7874 -0.4064)
			(end 0.7874 -0.4064)
			(stroke
				(width 0.1524)
				(type default)
			)
			(layer "F.SilkS")
		)
		(fp_line
			(start -0.7874 0.4064)
			(end -0.7874 -0.4064)
			(stroke
				(width 0.1524)
				(type default)
			)
			(layer "F.SilkS")
		)
		(fp_line
			(start 0.7874 -0.4064)
			(end 0.7874 0.4064)
			(stroke
				(width 0.1524)
				(type default)
			)
			(layer "F.SilkS")
		)
		(fp_line
			(start 0.7874 0.4064)
			(end -0.7874 0.4064)
			(stroke
				(width 0.1524)
				(type default)
			)
			(layer "F.SilkS")
		)
		(fp_line
			(start -0.67945 -0.305054)
			(end -0.12065 -0.305054)
			(stroke
				(width 0.1)
				(type default)
			)
			(layer "F.Fab")
		)
		(fp_line
			(start -0.67945 0.3048)
			(end -0.67945 -0.305054)
			(stroke
				(width 0.1)
				(type default)
			)
			(layer "F.Fab")
		)
		(fp_line
			(start -0.12065 -0.305054)
			(end -0.12065 -0.2794)
			(stroke
				(width 0.1)
				(type default)
			)
			(layer "F.Fab")
		)
		(fp_line
			(start -0.12065 -0.2794)
			(end 0.12065 -0.2794)
			(stroke
				(width 0.1)
				(type default)
			)
			(layer "F.Fab")
		)
		(fp_line
			(start -0.12065 0.2794)
			(end -0.12065 0.3048)
			(stroke
				(width 0.1)
				(type default)
			)
			(layer "F.Fab")
		)
		(fp_line
			(start -0.12065 0.3048)
			(end -0.67945 0.3048)
			(stroke
				(width 0.1)
				(type default)
			)
			(layer "F.Fab")
		)
		(fp_line
			(start 0.120396 0.2794)
			(end -0.12065 0.2794)
			(stroke
				(width 0.1)
				(type default)
			)
			(layer "F.Fab")
		)
		(fp_line
			(start 0.120396 0.3048)
			(end 0.120396 0.2794)
			(stroke
				(width 0.1)
				(type default)
			)
			(layer "F.Fab")
		)
		(fp_line
			(start 0.12065 -0.3048)
			(end 0.67945 -0.3048)
			(stroke
				(width 0.1)
				(type default)
			)
			(layer "F.Fab")
		)
		(fp_line
			(start 0.12065 -0.2794)
			(end 0.12065 -0.3048)
			(stroke
				(width 0.1)
				(type default)
			)
			(layer "F.Fab")
		)
		(fp_line
			(start 0.67945 -0.3048)
			(end 0.67945 0.3048)
			(stroke
				(width 0.1)
				(type default)
			)
			(layer "F.Fab")
		)
		(fp_line
			(start 0.67945 0.3048)
			(end 0.120396 0.3048)
			(stroke
				(width 0.1)
				(type default)
			)
			(layer "F.Fab")
		)
		(pad "1" smd circle
			(at -0.40005 0)
			(size 0 0)
			(layers "F.Cu" "F.Mask" "F.Paste")
			(net "SMB_1_BMC_GPU_BUF_R_SDA")
		)
		(pad "2" smd circle
			(at 0.40005 0)
			(size 0 0)
			(layers "F.Cu" "F.Mask" "F.Paste")
			(net "SMB_1_BMC_GPU_BUF_SDA")
		)
	)
	(footprint ""
		(layer "F.Cu")
		(at 305.826922 -47.991268)
		(property "Reference" "R3689"
			(at 0 0 0)
			(layer "F.SilkS")
			(hide yes)
			(effects
				(font
					(size 1.27 1.27)
				)
			)
		)
		(property "Value" ""
			(at 0 0 0)
			(layer "F.Fab")
			(effects
				(font
					(size 1.27 1.27)
				)
			)
		)
		(duplicate_pad_numbers_are_jumpers no)
		(fp_line
			(start -0.7874 -0.4064)
			(end 0.7874 -0.4064)
			(stroke
				(width 0.1524)
				(type default)
			)
			(layer "F.SilkS")
		)
		(fp_line
			(start -0.7874 0.4064)
			(end -0.7874 -0.4064)
			(stroke
				(width 0.1524)
				(type default)
			)
			(layer "F.SilkS")
		)
		(fp_line
			(start 0.7874 -0.4064)
			(end 0.7874 0.4064)
			(stroke
				(width 0.1524)
				(type default)
			)
			(layer "F.SilkS")
		)
		(fp_line
			(start 0.7874 0.4064)
			(end -0.7874 0.4064)
			(stroke
				(width 0.1524)
				(type default)
			)
			(layer "F.SilkS")
		)
		(fp_line
			(start -0.67945 -0.305054)
			(end -0.12065 -0.305054)
			(stroke
				(width 0.1)
				(type default)
			)
			(layer "F.Fab")
		)
		(fp_line
			(start -0.67945 0.3048)
			(end -0.67945 -0.305054)
			(stroke
				(width 0.1)
				(type default)
			)
			(layer "F.Fab")
		)
		(fp_line
			(start -0.12065 -0.305054)
			(end -0.12065 -0.2794)
			(stroke
				(width 0.1)
				(type default)
			)
			(layer "F.Fab")
		)
		(fp_line
			(start -0.12065 -0.2794)
			(end 0.12065 -0.2794)
			(stroke
				(width 0.1)
				(type default)
			)
			(layer "F.Fab")
		)
		(fp_line
			(start -0.12065 0.2794)
			(end -0.12065 0.3048)
			(stroke
				(width 0.1)
				(type default)
			)
			(layer "F.Fab")
		)
		(fp_line
			(start -0.12065 0.3048)
			(end -0.67945 0.3048)
			(stroke
				(width 0.1)
				(type default)
			)
			(layer "F.Fab")
		)
		(fp_line
			(start 0.120396 0.2794)
			(end -0.12065 0.2794)
			(stroke
				(width 0.1)
				(type default)
			)
			(layer "F.Fab")
		)
		(fp_line
			(start 0.120396 0.3048)
			(end 0.120396 0.2794)
			(stroke
				(width 0.1)
				(type default)
			)
			(layer "F.Fab")
		)
		(fp_line
			(start 0.12065 -0.3048)
			(end 0.67945 -0.3048)
			(stroke
				(width 0.1)
				(type default)
			)
			(layer "F.Fab")
		)
		(fp_line
			(start 0.12065 -0.2794)
			(end 0.12065 -0.3048)
			(stroke
				(width 0.1)
				(type default)
			)
			(layer "F.Fab")
		)
		(fp_line
			(start 0.67945 -0.3048)
			(end 0.67945 0.3048)
			(stroke
				(width 0.1)
				(type default)
			)
			(layer "F.Fab")
		)
		(fp_line
			(start 0.67945 0.3048)
			(end 0.120396 0.3048)
			(stroke
				(width 0.1)
				(type default)
			)
			(layer "F.Fab")
		)
		(pad "1" smd circle
			(at -0.40005 0)
			(size 0 0)
			(layers "F.Cu" "F.Mask" "F.Paste")
			(net "P3V3_ADC128_VCC")
		)
		(pad "2" smd circle
			(at 0.40005 0)
			(size 0 0)
			(layers "F.Cu" "F.Mask" "F.Paste")
			(net "ADC128_VREF")
		)
	)
	(footprint ""
		(layer "F.Cu")
		(at 400.518122 -172.3136 -90)
		(property "Reference" "PC577_7"
			(at 0 0 270)
			(layer "F.SilkS")
			(hide yes)
			(effects
				(font
					(size 1.27 1.27)
				)
			)
		)
		(property "Value" ""
			(at 0 0 270)
			(layer "F.Fab")
			(effects
				(font
					(size 1.27 1.27)
				)
			)
		)
		(duplicate_pad_numbers_are_jumpers no)
		(fp_line
			(start -0.7874 0.4064)
			(end -0.7874 -0.4064)
			(stroke
				(width 0.1524)
				(type default)
			)
			(layer "F.SilkS")
		)
		(fp_line
			(start 0.7874 0.4064)
			(end -0.7874 0.4064)
			(stroke
				(width 0.1524)
				(type default)
			)
			(layer "F.SilkS")
		)
		(fp_line
			(start -0.7874 -0.4064)
			(end 0.7874 -0.4064)
			(stroke
				(width 0.1524)
				(type default)
			)
			(layer "F.SilkS")
		)
		(fp_line
			(start 0.7874 -0.4064)
			(end 0.7874 0.4064)
			(stroke
				(width 0.1524)
				(type default)
			)
			(layer "F.SilkS")
		)
		(fp_line
			(start -0.67945 0.3048)
			(end -0.67945 -0.305054)
			(stroke
				(width 0.1)
				(type default)
			)
			(layer "F.Fab")
		)
		(fp_line
			(start -0.12065 0.3048)
			(end -0.67945 0.3048)
			(stroke
				(width 0.1)
				(type default)
			)
			(layer "F.Fab")
		)
		(fp_line
			(start 0.120396 0.3048)
			(end 0.120396 0.2794)
			(stroke
				(width 0.1)
				(type default)
			)
			(layer "F.Fab")
		)
		(fp_line
			(start 0.67945 0.3048)
			(end 0.120396 0.3048)
			(stroke
				(width 0.1)
				(type default)
			)
			(layer "F.Fab")
		)
		(fp_line
			(start -0.12065 0.2794)
			(end -0.12065 0.3048)
			(stroke
				(width 0.1)
				(type default)
			)
			(layer "F.Fab")
		)
		(fp_line
			(start 0.120396 0.2794)
			(end -0.12065 0.2794)
			(stroke
				(width 0.1)
				(type default)
			)
			(layer "F.Fab")
		)
		(fp_line
			(start -0.12065 -0.2794)
			(end 0.12065 -0.2794)
			(stroke
				(width 0.1)
				(type default)
			)
			(layer "F.Fab")
		)
		(fp_line
			(start 0.12065 -0.2794)
			(end 0.12065 -0.3048)
			(stroke
				(width 0.1)
				(type default)
			)
			(layer "F.Fab")
		)
		(fp_line
			(start 0.12065 -0.3048)
			(end 0.67945 -0.3048)
			(stroke
				(width 0.1)
				(type default)
			)
			(layer "F.Fab")
		)
		(fp_line
			(start 0.67945 -0.3048)
			(end 0.67945 0.3048)
			(stroke
				(width 0.1)
				(type default)
			)
			(layer "F.Fab")
		)
		(fp_line
			(start -0.67945 -0.305054)
			(end -0.12065 -0.305054)
			(stroke
				(width 0.1)
				(type default)
			)
			(layer "F.Fab")
		)
		(fp_line
			(start -0.12065 -0.305054)
			(end -0.12065 -0.2794)
			(stroke
				(width 0.1)
				(type default)
			)
			(layer "F.Fab")
		)
		(pad "1" smd circle
			(at -0.40005 0 270)
			(size 0 0)
			(layers "F.Cu" "F.Mask" "F.Paste")
			(net "PVDDCR_CPU0_P0_VCCS")
		)
		(pad "2" smd circle
			(at 0.40005 0 270)
			(size 0 0)
			(layers "F.Cu" "F.Mask" "F.Paste")
			(net "GND")
		)
	)
	(footprint ""
		(layer "F.Cu")
		(at 65.861438 -22.235922 180)
		(property "Reference" "PR3850"
			(at 0 0 180)
			(layer "F.SilkS")
			(hide yes)
			(effects
				(font
					(size 1.27 1.27)
				)
			)
		)
		(property "Value" ""
			(at 0 0 180)
			(layer "F.Fab")
			(effects
				(font
					(size 1.27 1.27)
				)
			)
		)
		(duplicate_pad_numbers_are_jumpers no)
		(fp_line
			(start 0.7874 0.4064)
			(end -0.7874 0.4064)
			(stroke
				(width 0.1524)
				(type default)
			)
			(layer "F.SilkS")
		)
		(fp_line
			(start 0.7874 -0.4064)
			(end 0.7874 0.4064)
			(stroke
				(width 0.1524)
				(type default)
			)
			(layer "F.SilkS")
		)
		(fp_line
			(start -0.7874 0.4064)
			(end -0.7874 -0.4064)
			(stroke
				(width 0.1524)
				(type default)
			)
			(layer "F.SilkS")
		)
		(fp_line
			(start -0.7874 -0.4064)
			(end 0.7874 -0.4064)
			(stroke
				(width 0.1524)
				(type default)
			)
			(layer "F.SilkS")
		)
		(fp_line
			(start 0.67945 0.3048)
			(end 0.120396 0.3048)
			(stroke
				(width 0.1)
				(type default)
			)
			(layer "F.Fab")
		)
		(fp_line
			(start 0.67945 -0.3048)
			(end 0.67945 0.3048)
			(stroke
				(width 0.1)
				(type default)
			)
			(layer "F.Fab")
		)
		(fp_line
			(start 0.12065 -0.2794)
			(end 0.12065 -0.3048)
			(stroke
				(width 0.1)
				(type default)
			)
			(layer "F.Fab")
		)
		(fp_line
			(start 0.12065 -0.3048)
			(end 0.67945 -0.3048)
			(stroke
				(width 0.1)
				(type default)
			)
			(layer "F.Fab")
		)
		(fp_line
			(start 0.120396 0.3048)
			(end 0.120396 0.2794)
			(stroke
				(width 0.1)
				(type default)
			)
			(layer "F.Fab")
		)
		(fp_line
			(start 0.120396 0.2794)
			(end -0.12065 0.2794)
			(stroke
				(width 0.1)
				(type default)
			)
			(layer "F.Fab")
		)
		(fp_line
			(start -0.12065 0.3048)
			(end -0.67945 0.3048)
			(stroke
				(width 0.1)
				(type default)
			)
			(layer "F.Fab")
		)
		(fp_line
			(start -0.12065 0.2794)
			(end -0.12065 0.3048)
			(stroke
				(width 0.1)
				(type default)
			)
			(layer "F.Fab")
		)
		(fp_line
			(start -0.12065 -0.2794)
			(end 0.12065 -0.2794)
			(stroke
				(width 0.1)
				(type default)
			)
			(layer "F.Fab")
		)
		(fp_line
			(start -0.12065 -0.305054)
			(end -0.12065 -0.2794)
			(stroke
				(width 0.1)
				(type default)
			)
			(layer "F.Fab")
		)
		(fp_line
			(start -0.67945 0.3048)
			(end -0.67945 -0.305054)
			(stroke
				(width 0.1)
				(type default)
			)
			(layer "F.Fab")
		)
		(fp_line
			(start -0.67945 -0.305054)
			(end -0.12065 -0.305054)
			(stroke
				(width 0.1)
				(type default)
			)
			(layer "F.Fab")
		)
		(pad "1" smd circle
			(at -0.40005 0 180)
			(size 0 0)
			(layers "F.Cu" "F.Mask" "F.Paste")
			(net "P12V_OCP_V3_2")
		)
		(pad "2" smd circle
			(at 0.40005 0 180)
			(size 0 0)
			(layers "F.Cu" "F.Mask" "F.Paste")
			(net "P12V_OCP_AVIN_PD_2")
		)
	)
	(footprint ""
		(layer "F.Cu")
		(at 297.486324 -113.751614 180)
		(property "Reference" "R2984"
			(at 0 0 180)
			(layer "F.SilkS")
			(hide yes)
			(effects
				(font
					(size 1.27 1.27)
				)
			)
		)
		(property "Value" ""
			(at 0 0 180)
			(layer "F.Fab")
			(effects
				(font
					(size 1.27 1.27)
				)
			)
		)
		(duplicate_pad_numbers_are_jumpers no)
		(fp_line
			(start 0.7874 0.4064)
			(end -0.7874 0.4064)
			(stroke
				(width 0.1524)
				(type default)
			)
			(layer "F.SilkS")
		)
		(fp_line
			(start 0.7874 -0.4064)
			(end 0.7874 0.4064)
			(stroke
				(width 0.1524)
				(type default)
			)
			(layer "F.SilkS")
		)
		(fp_line
			(start -0.7874 0.4064)
			(end -0.7874 -0.4064)
			(stroke
				(width 0.1524)
				(type default)
			)
			(layer "F.SilkS")
		)
		(fp_line
			(start -0.7874 -0.4064)
			(end 0.7874 -0.4064)
			(stroke
				(width 0.1524)
				(type default)
			)
			(layer "F.SilkS")
		)
		(fp_line
			(start 0.67945 0.3048)
			(end 0.120396 0.3048)
			(stroke
				(width 0.1)
				(type default)
			)
			(layer "F.Fab")
		)
		(fp_line
			(start 0.67945 -0.3048)
			(end 0.67945 0.3048)
			(stroke
				(width 0.1)
				(type default)
			)
			(layer "F.Fab")
		)
		(fp_line
			(start 0.12065 -0.2794)
			(end 0.12065 -0.3048)
			(stroke
				(width 0.1)
				(type default)
			)
			(layer "F.Fab")
		)
		(fp_line
			(start 0.12065 -0.3048)
			(end 0.67945 -0.3048)
			(stroke
				(width 0.1)
				(type default)
			)
			(layer "F.Fab")
		)
		(fp_line
			(start 0.120396 0.3048)
			(end 0.120396 0.2794)
			(stroke
				(width 0.1)
				(type default)
			)
			(layer "F.Fab")
		)
		(fp_line
			(start 0.120396 0.2794)
			(end -0.12065 0.2794)
			(stroke
				(width 0.1)
				(type default)
			)
			(layer "F.Fab")
		)
		(fp_line
			(start -0.12065 0.3048)
			(end -0.67945 0.3048)
			(stroke
				(width 0.1)
				(type default)
			)
			(layer "F.Fab")
		)
		(fp_line
			(start -0.12065 0.2794)
			(end -0.12065 0.3048)
			(stroke
				(width 0.1)
				(type default)
			)
			(layer "F.Fab")
		)
		(fp_line
			(start -0.12065 -0.2794)
			(end 0.12065 -0.2794)
			(stroke
				(width 0.1)
				(type default)
			)
			(layer "F.Fab")
		)
		(fp_line
			(start -0.12065 -0.305054)
			(end -0.12065 -0.2794)
			(stroke
				(width 0.1)
				(type default)
			)
			(layer "F.Fab")
		)
		(fp_line
			(start -0.67945 0.3048)
			(end -0.67945 -0.305054)
			(stroke
				(width 0.1)
				(type default)
			)
			(layer "F.Fab")
		)
		(fp_line
			(start -0.67945 -0.305054)
			(end -0.12065 -0.305054)
			(stroke
				(width 0.1)
				(type default)
			)
			(layer "F.Fab")
		)
		(pad "1" smd circle
			(at -0.40005 0 180)
			(size 0 0)
			(layers "F.Cu" "F.Mask" "F.Paste")
			(net "P3V3_AUX")
		)
		(pad "2" smd circle
			(at 0.40005 0 180)
			(size 0 0)
			(layers "F.Cu" "F.Mask" "F.Paste")
			(net "SMB_BMC_SWB_SCL")
		)
	)
	(footprint ""
		(layer "F.Cu")
		(at 407.12644 -378.95403 -90)
		(property "Reference" "C857"
			(at 0 0 270)
			(layer "F.SilkS")
			(hide yes)
			(effects
				(font
					(size 1.27 1.27)
				)
			)
		)
		(property "Value" ""
			(at 0 0 270)
			(layer "F.Fab")
			(effects
				(font
					(size 1.27 1.27)
				)
			)
		)
		(duplicate_pad_numbers_are_jumpers no)
		(fp_line
			(start -0.299974 0.150114)
			(end -0.299974 -0.150114)
			(stroke
				(width 0.1)
				(type default)
			)
			(layer "F.Fab")
		)
		(fp_line
			(start 0.299974 0.150114)
			(end -0.299974 0.150114)
			(stroke
				(width 0.1)
				(type default)
			)
			(layer "F.Fab")
		)
		(fp_line
			(start -0.299974 -0.150114)
			(end 0.299974 -0.150114)
			(stroke
				(width 0.1)
				(type default)
			)
			(layer "F.Fab")
		)
		(fp_line
			(start 0.299974 -0.150114)
			(end 0.299974 0.150114)
			(stroke
				(width 0.1)
				(type default)
			)
			(layer "F.Fab")
		)
		(pad "1" smd rect
			(at -0.2667 0 270)
			(size 0.3048 0.381)
			(layers "F.Cu" "F.Mask" "F.Paste")
			(net "P5E_CPU0_P2_TX_C_DP<6>")
		)
		(pad "2" smd rect
			(at 0.2667 0 270)
			(size 0.3048 0.381)
			(layers "F.Cu" "F.Mask" "F.Paste")
			(net "P5E_CPU0_P2_TX_DP<6>")
		)
	)
	(footprint ""
		(layer "F.Cu")
		(at 436.052722 -409.68676)
		(property "Reference" "R1401"
			(at 0 0 0)
			(layer "F.SilkS")
			(hide yes)
			(effects
				(font
					(size 1.27 1.27)
				)
			)
		)
		(property "Value" ""
			(at 0 0 0)
			(layer "F.Fab")
			(effects
				(font
					(size 1.27 1.27)
				)
			)
		)
		(duplicate_pad_numbers_are_jumpers no)
		(fp_line
			(start -0.32512 -0.175006)
			(end 0.32512 -0.175006)
			(stroke
				(width 0.1)
				(type default)
			)
			(layer "F.Fab")
		)
		(fp_line
			(start -0.32512 0.175006)
			(end -0.32512 -0.175006)
			(stroke
				(width 0.1)
				(type default)
			)
			(layer "F.Fab")
		)
		(fp_line
			(start 0.32512 -0.175006)
			(end 0.32512 0.175006)
			(stroke
				(width 0.1)
				(type default)
			)
			(layer "F.Fab")
		)
		(fp_line
			(start 0.32512 0.175006)
			(end -0.32512 0.175006)
			(stroke
				(width 0.1)
				(type default)
			)
			(layer "F.Fab")
		)
		(pad "1" smd rect
			(at -0.2667 0)
			(size 0.3048 0.381)
			(layers "F.Cu" "F.Mask" "F.Paste")
			(net "JTAG_TCK_RT_CPU0_P2")
		)
		(pad "2" smd rect
			(at 0.2667 0 180)
			(size 0.3048 0.381)
			(layers "F.Cu" "F.Mask" "F.Paste")
			(net "GND")
		)
	)
)
